(kicad_pcb
	(version 20241229)
	(generator "pcbnew")
	(generator_version "9.0")
	(general
		(thickness 1.62)
		(legacy_teardrops no)
	)
	(paper "A3")
	(title_block
		(title "COM Express 7 Baseboard")
		(date "2025-02-04")
		(rev "1.1.2")
		(company "Antmicro Ltd")
		(comment 1 "www.antmicro.com")
		(comment 9 "footprint 690 of 802 (U40), pads 1-42 of 57")
	)
	(layers
		(0 "F.Cu" signal)
		(4 "In1.Cu" signal)
		(6 "In2.Cu" signal)
		(8 "In3.Cu" signal)
		(10 "In4.Cu" signal)
		(12 "In5.Cu" signal)
		(14 "In6.Cu" signal)
		(2 "B.Cu" signal)
		(9 "F.Adhes" user "F.Adhesive")
		(11 "B.Adhes" user "B.Adhesive")
		(13 "F.Paste" user)
		(15 "B.Paste" user)
		(5 "F.SilkS" user "F.Silkscreen")
		(7 "B.SilkS" user "B.Silkscreen")
		(1 "F.Mask" user)
		(3 "B.Mask" user)
		(17 "Dwgs.User" user "User.Drawings")
		(19 "Cmts.User" user "User.Comments")
		(21 "Eco1.User" user "User.Eco1")
		(23 "Eco2.User" user "User.Eco2")
		(25 "Edge.Cuts" user)
		(27 "Margin" user)
		(31 "F.CrtYd" user "F.Courtyard")
		(29 "B.CrtYd" user "B.Courtyard")
		(35 "F.Fab" user)
		(33 "B.Fab" user)
	)
	(footprint "antmicro-footprints:WQFN-42-1EP_3.5x9mm_P0.5mm"
		(layer "B.Cu")
		(at 193.591857 135.943686 -45)
		(descr "WQFN, 42 Pin (http://www.ti.com/lit/ds/symlink/ts3l501e.pdf#page=23), generated with kicad-footprint-generator ipc_noLead_generator.py")
		(tags "WQFN NoLead")
		(property "Reference" "U40"
			(at -0.166554 5.195942 135)
			(layer "B.SilkS")
			(effects
				(font
					(size 0.7 0.7)
					(thickness 0.15)
				)
				(justify left top mirror)
			)
		)
		(property "Value" "PI3EQX16904GL"
			(at 0 -5.819999 135)
			(layer "B.Fab")
			(effects
				(font
					(size 0.7 0.7)
					(thickness 0.15)
				)
				(justify left top mirror)
			)
		)
		(property "Datasheet" "https://www.diodes.com/part/view/PI3EQX16904GL"
			(at 0 0 135)
			(layer "B.Fab")
			(hide yes)
			(effects
				(font
					(size 1.27 1.27)
					(thickness 0.15)
				)
				(justify mirror)
			)
		)
		(property "Author" "Antmicro"
			(at 53.727 -324.573 45)
			(layer "B.Fab")
			(hide yes)
			(effects
				(font
					(size 1 1)
					(thickness 0.15)
				)
				(justify mirror)
			)
		)
		(property "License" "Apache-2.0"
			(at 53.727 -324.573 45)
			(layer "B.Fab")
			(hide yes)
			(effects
				(font
					(size 1 1)
					(thickness 0.15)
				)
				(justify mirror)
			)
		)
		(property "MPN" "PI3EQX16904GLZHEX"
			(at 53.727 -324.573 45)
			(layer "B.Fab")
			(hide yes)
			(effects
				(font
					(size 1 1)
					(thickness 0.15)
				)
				(justify mirror)
			)
		)
		(property "Manufacturer" "Diodes Incorporated"
			(at 53.727 -324.573 45)
			(layer "B.Fab")
			(hide yes)
			(effects
				(font
					(size 1 1)
					(thickness 0.15)
				)
				(justify mirror)
			)
		)
		(sheetname "PCIe redriver")
		(sheetfile "pcie_redriver.kicad_sch")
		(attr smd)
		(pad "" smd roundrect
			(at -0.51 -2.16 315)
			(size 0.83 0.87)
			(layers "B.Paste")
			(roundrect_rratio 0.25)
			(teardrops
				(best_length_ratio 0.2)
				(max_length 1)
				(best_width_ratio 0.9)
				(max_width 2)
				(curved_edges yes)
				(filter_ratio 0.9)
				(enabled yes)
				(allow_two_segments yes)
				(prefer_zone_connections yes)
			)
		)
		(pad "" smd roundrect
			(at -0.51 -1.08 315)
			(size 0.83 0.87)
			(layers "B.Paste")
			(roundrect_rratio 0.25)
			(teardrops
				(best_length_ratio 0.2)
				(max_length 1)
				(best_width_ratio 0.9)
				(max_width 2)
				(curved_edges yes)
				(filter_ratio 0.9)
				(enabled yes)
				(allow_two_segments yes)
				(prefer_zone_connections yes)
			)
		)
		(pad "" smd roundrect
			(at -0.51 1.081 315)
			(size 0.83 0.87)
			(layers "B.Paste")
			(roundrect_rratio 0.25)
			(teardrops
				(best_length_ratio 0.2)
				(max_length 1)
				(best_width_ratio 0.9)
				(max_width 2)
				(curved_edges yes)
				(filter_ratio 0.9)
				(enabled yes)
				(allow_two_segments yes)
				(prefer_zone_connections yes)
			)
		)
		(pad "" smd roundrect
			(at -0.51 2.161 315)
			(size 0.83 0.87)
			(layers "B.Paste")
			(roundrect_rratio 0.25)
			(teardrops
				(best_length_ratio 0.2)
				(max_length 1)
				(best_width_ratio 0.9)
				(max_width 2)
				(curved_edges yes)
				(filter_ratio 0.9)
				(enabled yes)
				(allow_two_segments yes)
				(prefer_zone_connections yes)
			)
		)
		(pad "" smd roundrect
			(at -0.51 3.242 315)
			(size 0.83 0.87)
			(layers "B.Paste")
			(roundrect_rratio 0.25)
			(teardrops
				(best_length_ratio 0.2)
				(max_length 1)
				(best_width_ratio 0.9)
				(max_width 2)
				(curved_edges yes)
				(filter_ratio 0.9)
				(enabled yes)
				(allow_two_segments yes)
				(prefer_zone_connections yes)
			)
		)
		(pad "" smd roundrect
			(at -0.509999 -3.24 315)
			(size 0.83 0.87)
			(layers "B.Paste")
			(roundrect_rratio 0.25)
			(teardrops
				(best_length_ratio 0.2)
				(max_length 1)
				(best_width_ratio 0.9)
				(max_width 2)
				(curved_edges yes)
				(filter_ratio 0.9)
				(enabled yes)
				(allow_two_segments yes)
				(prefer_zone_connections yes)
			)
		)
		(pad "" smd roundrect
			(at -0.509999 0 315)
			(size 0.83 0.87)
			(layers "B.Paste")
			(roundrect_rratio 0.25)
			(teardrops
				(best_length_ratio 0.2)
				(max_length 1)
				(best_width_ratio 0.9)
				(max_width 2)
				(curved_edges yes)
				(filter_ratio 0.9)
				(enabled yes)
				(allow_two_segments yes)
				(prefer_zone_connections yes)
			)
		)
		(pad "" smd roundrect
			(at 0.508 -3.24 315)
			(size 0.83 0.87)
			(layers "B.Paste")
			(roundrect_rratio 0.25)
			(teardrops
				(best_length_ratio 0.2)
				(max_length 1)
				(best_width_ratio 0.9)
				(max_width 2)
				(curved_edges yes)
				(filter_ratio 0.9)
				(enabled yes)
				(allow_two_segments yes)
				(prefer_zone_connections yes)
			)
		)
		(pad "" smd roundrect
			(at 0.508 -2.16 315)
			(size 0.83 0.87)
			(layers "B.Paste")
			(roundrect_rratio 0.25)
			(teardrops
				(best_length_ratio 0.2)
				(max_length 1)
				(best_width_ratio 0.9)
				(max_width 2)
				(curved_edges yes)
				(filter_ratio 0.9)
				(enabled yes)
				(allow_two_segments yes)
				(prefer_zone_connections yes)
			)
		)
		(pad "" smd roundrect
			(at 0.508 -1.08 315)
			(size 0.83 0.87)
			(layers "B.Paste")
			(roundrect_rratio 0.25)
			(teardrops
				(best_length_ratio 0.2)
				(max_length 1)
				(best_width_ratio 0.9)
				(max_width 2)
				(curved_edges yes)
				(filter_ratio 0.9)
				(enabled yes)
				(allow_two_segments yes)
				(prefer_zone_connections yes)
			)
		)
		(pad "" smd roundrect
			(at 0.508 0 315)
			(size 0.83 0.87)
			(layers "B.Paste")
			(roundrect_rratio 0.25)
			(teardrops
				(best_length_ratio 0.2)
				(max_length 1)
				(best_width_ratio 0.9)
				(max_width 2)
				(curved_edges yes)
				(filter_ratio 0.9)
				(enabled yes)
				(allow_two_segments yes)
				(prefer_zone_connections yes)
			)
		)
		(pad "" smd roundrect
			(at 0.508 1.081 315)
			(size 0.83 0.87)
			(layers "B.Paste")
			(roundrect_rratio 0.25)
			(teardrops
				(best_length_ratio 0.2)
				(max_length 1)
				(best_width_ratio 0.9)
				(max_width 2)
				(curved_edges yes)
				(filter_ratio 0.9)
				(enabled yes)
				(allow_two_segments yes)
				(prefer_zone_connections yes)
			)
		)
		(pad "" smd roundrect
			(at 0.508 2.161 315)
			(size 0.83 0.87)
			(layers "B.Paste")
			(roundrect_rratio 0.25)
			(teardrops
				(best_length_ratio 0.2)
				(max_length 1)
				(best_width_ratio 0.9)
				(max_width 2)
				(curved_edges yes)
				(filter_ratio 0.9)
				(enabled yes)
				(allow_two_segments yes)
				(prefer_zone_connections yes)
			)
		)
		(pad "" smd roundrect
			(at 0.508 3.242 315)
			(size 0.83 0.87)
			(layers "B.Paste")
			(roundrect_rratio 0.25)
			(teardrops
				(best_length_ratio 0.2)
				(max_length 1)
				(best_width_ratio 0.9)
				(max_width 2)
				(curved_edges yes)
				(filter_ratio 0.9)
				(enabled yes)
				(allow_two_segments yes)
				(prefer_zone_connections yes)
			)
		)
		(pad "1" smd roundrect
			(at -1.688 4 315)
			(size 0.875 0.25)
			(layers "B.Cu" "B.Mask" "B.Paste")
			(roundrect_rratio 0.25)
			(net 976 "/PCIe redriver/RX_EQ2")
			(pinfunction "EQ2")
			(pintype "passive")
			(teardrops
				(best_length_ratio 0.2)
				(max_length 1)
				(best_width_ratio 0.9)
				(max_width 2)
				(curved_edges yes)
				(filter_ratio 0.9)
				(enabled yes)
				(allow_two_segments yes)
				(prefer_zone_connections yes)
			)
		)
		(pad "2" smd roundrect
			(at -1.688 3.5 315)
			(size 0.875 0.25)
			(layers "B.Cu" "B.Mask" "B.Paste")
			(roundrect_rratio 0.25)
			(net 973 "/PCIe redriver/RX_SW")
			(pinfunction "SW1")
			(pintype "input")
			(teardrops
				(best_length_ratio 0.2)
				(max_length 1)
				(best_width_ratio 0.9)
				(max_width 2)
				(curved_edges yes)
				(filter_ratio 0.9)
				(enabled yes)
				(allow_two_segments yes)
				(prefer_zone_connections yes)
			)
		)
		(pad "3" smd roundrect
			(at -1.688 3 315)
			(size 0.875 0.25)
			(layers "B.Cu" "B.Mask" "B.Paste")
			(roundrect_rratio 0.25)
			(net 2 "+3V3")
			(pinfunction "VCC")
			(pintype "passive")
			(teardrops
				(best_length_ratio 0.2)
				(max_length 1)
				(best_width_ratio 0.9)
				(max_width 2)
				(curved_edges yes)
				(filter_ratio 0.9)
				(enabled yes)
				(allow_two_segments yes)
				(prefer_zone_connections yes)
			)
		)
		(pad "4" smd roundrect
			(at -1.688 2.5 315)
			(size 0.875 0.25)
			(layers "B.Cu" "B.Mask" "B.Paste")
			(roundrect_rratio 0.25)
			(net 196 "/OCuLink/PCIe_{x4}.RX3+")
			(pinfunction "A0RX+")
			(pintype "input")
			(teardrops
				(best_length_ratio 0.2)
				(max_length 1)
				(best_width_ratio 0.9)
				(max_width 2)
				(curved_edges yes)
				(filter_ratio 0.9)
				(enabled yes)
				(allow_two_segments yes)
				(prefer_zone_connections yes)
			)
		)
		(pad "5" smd roundrect
			(at -1.688 2 315)
			(size 0.875 0.25)
			(layers "B.Cu" "B.Mask" "B.Paste")
			(roundrect_rratio 0.25)
			(net 197 "/OCuLink/PCIe_{x4}.RX3-")
			(pinfunction "A0RX-")
			(pintype "input")
			(teardrops
				(best_length_ratio 0.2)
				(max_length 1)
				(best_width_ratio 0.9)
				(max_width 2)
				(curved_edges yes)
				(filter_ratio 0.9)
				(enabled yes)
				(allow_two_segments yes)
				(prefer_zone_connections yes)
			)
		)
		(pad "6" smd roundrect
			(at -1.688 1.5 315)
			(size 0.875 0.25)
			(layers "B.Cu" "B.Mask" "B.Paste")
			(roundrect_rratio 0.25)
			(net 2 "+3V3")
			(pinfunction "VCC")
			(pintype "passive")
			(teardrops
				(best_length_ratio 0.2)
				(max_length 1)
				(best_width_ratio 0.9)
				(max_width 2)
				(curved_edges yes)
				(filter_ratio 0.9)
				(enabled yes)
				(allow_two_segments yes)
				(prefer_zone_connections yes)
			)
		)
		(pad "7" smd roundrect
			(at -1.688 1 315)
			(size 0.875 0.25)
			(layers "B.Cu" "B.Mask" "B.Paste")
			(roundrect_rratio 0.25)
			(net 194 "/OCuLink/PCIe_{x4}.RX2+")
			(pinfunction "A1RX+")
			(pintype "input")
			(teardrops
				(best_length_ratio 0.2)
				(max_length 1)
				(best_width_ratio 0.9)
				(max_width 2)
				(curved_edges yes)
				(filter_ratio 0.9)
				(enabled yes)
				(allow_two_segments yes)
				(prefer_zone_connections yes)
			)
		)
		(pad "8" smd roundrect
			(at -1.688 0.5 315)
			(size 0.875 0.25)
			(layers "B.Cu" "B.Mask" "B.Paste")
			(roundrect_rratio 0.25)
			(net 195 "/OCuLink/PCIe_{x4}.RX2-")
			(pinfunction "A1RX-")
			(pintype "input")
			(teardrops
				(best_length_ratio 0.2)
				(max_length 1)
				(best_width_ratio 0.9)
				(max_width 2)
				(curved_edges yes)
				(filter_ratio 0.9)
				(enabled yes)
				(allow_two_segments yes)
				(prefer_zone_connections yes)
			)
		)
		(pad "9" smd roundrect
			(at -1.688 0 315)
			(size 0.875 0.25)
			(layers "B.Cu" "B.Mask" "B.Paste")
			(roundrect_rratio 0.25)
			(net 2 "+3V3")
			(pinfunction "VCC")
			(pintype "passive")
			(teardrops
				(best_length_ratio 0.2)
				(max_length 1)
				(best_width_ratio 0.9)
				(max_width 2)
				(curved_edges yes)
				(filter_ratio 0.9)
				(enabled yes)
				(allow_two_segments yes)
				(prefer_zone_connections yes)
			)
		)
		(pad "10" smd roundrect
			(at -1.688 -0.5 315)
			(size 0.875 0.25)
			(layers "B.Cu" "B.Mask" "B.Paste")
			(roundrect_rratio 0.25)
			(net 188 "/OCuLink/PCIe_{x4}.RX1+")
			(pinfunction "A2RX+")
			(pintype "input")
			(teardrops
				(best_length_ratio 0.2)
				(max_length 1)
				(best_width_ratio 0.9)
				(max_width 2)
				(curved_edges yes)
				(filter_ratio 0.9)
				(enabled yes)
				(allow_two_segments yes)
				(prefer_zone_connections yes)
			)
		)
		(pad "11" smd roundrect
			(at -1.688 -1 315)
			(size 0.875 0.25)
			(layers "B.Cu" "B.Mask" "B.Paste")
			(roundrect_rratio 0.25)
			(net 189 "/OCuLink/PCIe_{x4}.RX1-")
			(pinfunction "A2RX-")
			(pintype "input")
			(teardrops
				(best_length_ratio 0.2)
				(max_length 1)
				(best_width_ratio 0.9)
				(max_width 2)
				(curved_edges yes)
				(filter_ratio 0.9)
				(enabled yes)
				(allow_two_segments yes)
				(prefer_zone_connections yes)
			)
		)
		(pad "12" smd roundrect
			(at -1.688 -1.5 315)
			(size 0.875 0.25)
			(layers "B.Cu" "B.Mask" "B.Paste")
			(roundrect_rratio 0.25)
			(net 2 "+3V3")
			(pinfunction "VCC")
			(pintype "power_in")
			(teardrops
				(best_length_ratio 0.2)
				(max_length 1)
				(best_width_ratio 0.9)
				(max_width 2)
				(curved_edges yes)
				(filter_ratio 0.9)
				(enabled yes)
				(allow_two_segments yes)
				(prefer_zone_connections yes)
			)
		)
		(pad "13" smd roundrect
			(at -1.688 -2 315)
			(size 0.875 0.25)
			(layers "B.Cu" "B.Mask" "B.Paste")
			(roundrect_rratio 0.25)
			(net 186 "/OCuLink/PCIe_{x4}.RX0+")
			(pinfunction "A3RX+")
			(pintype "input")
			(teardrops
				(best_length_ratio 0.2)
				(max_length 1)
				(best_width_ratio 0.9)
				(max_width 2)
				(curved_edges yes)
				(filter_ratio 0.9)
				(enabled yes)
				(allow_two_segments yes)
				(prefer_zone_connections yes)
			)
		)
		(pad "14" smd roundrect
			(at -1.688 -2.5 315)
			(size 0.875 0.25)
			(layers "B.Cu" "B.Mask" "B.Paste")
			(roundrect_rratio 0.25)
			(net 187 "/OCuLink/PCIe_{x4}.RX0-")
			(pinfunction "A3RX-")
			(pintype "input")
			(teardrops
				(best_length_ratio 0.2)
				(max_length 1)
				(best_width_ratio 0.9)
				(max_width 2)
				(curved_edges yes)
				(filter_ratio 0.9)
				(enabled yes)
				(allow_two_segments yes)
				(prefer_zone_connections yes)
			)
		)
		(pad "15" smd roundrect
			(at -1.688 -3 315)
			(size 0.875 0.25)
			(layers "B.Cu" "B.Mask" "B.Paste")
			(roundrect_rratio 0.25)
			(net 2 "+3V3")
			(pinfunction "VCC")
			(pintype "passive")
			(teardrops
				(best_length_ratio 0.2)
				(max_length 1)
				(best_width_ratio 0.9)
				(max_width 2)
				(curved_edges yes)
				(filter_ratio 0.9)
				(enabled yes)
				(allow_two_segments yes)
				(prefer_zone_connections yes)
			)
		)
		(pad "16" smd roundrect
			(at -1.688 -3.5 315)
			(size 0.875 0.25)
			(layers "B.Cu" "B.Mask" "B.Paste")
			(roundrect_rratio 0.25)
			(net 719 "Net-(U40-~{I2C_{RESET}})")
			(pinfunction "~{I2C_{RESET}}")
			(pintype "input")
			(teardrops
				(best_length_ratio 0.2)
				(max_length 1)
				(best_width_ratio 0.9)
				(max_width 2)
				(curved_edges yes)
				(filter_ratio 0.9)
				(enabled yes)
				(allow_two_segments yes)
				(prefer_zone_connections yes)
			)
		)
		(pad "17" smd roundrect
			(at -1.688 -4 315)
			(size 0.875 0.25)
			(layers "B.Cu" "B.Mask" "B.Paste")
			(roundrect_rratio 0.25)
			(net 1 "GND")
			(pinfunction "AD1")
			(pintype "passive")
			(teardrops
				(best_length_ratio 0.2)
				(max_length 1)
				(best_width_ratio 0.9)
				(max_width 2)
				(curved_edges yes)
				(filter_ratio 0.9)
				(enabled yes)
				(allow_two_segments yes)
				(prefer_zone_connections yes)
			)
		)
		(pad "18" smd roundrect
			(at -0.75 -4.437 315)
			(size 0.25 0.875)
			(layers "B.Cu" "B.Mask" "B.Paste")
			(roundrect_rratio 0.25)
			(net 716 "Net-(U40-SDA)")
			(pinfunction "SDA")
			(pintype "open_collector")
			(teardrops
				(best_length_ratio 0.2)
				(max_length 1)
				(best_width_ratio 0.9)
				(max_width 2)
				(curved_edges yes)
				(filter_ratio 0.9)
				(enabled yes)
				(allow_two_segments yes)
				(prefer_zone_connections yes)
			)
		)
		(pad "19" smd roundrect
			(at -0.25 -4.437 315)
			(size 0.25 0.875)
			(layers "B.Cu" "B.Mask" "B.Paste")
			(roundrect_rratio 0.25)
			(net 717 "Net-(U40-SCL)")
			(pinfunction "SCL")
			(pintype "open_collector")
			(teardrops
				(best_length_ratio 0.2)
				(max_length 1)
				(best_width_ratio 0.9)
				(max_width 2)
				(curved_edges yes)
				(filter_ratio 0.9)
				(enabled yes)
				(allow_two_segments yes)
				(prefer_zone_connections yes)
			)
		)
		(pad "20" smd roundrect
			(at 0.25 -4.437 315)
			(size 0.25 0.875)
			(layers "B.Cu" "B.Mask" "B.Paste")
			(roundrect_rratio 0.25)
			(net 945 "/GPIO expander/GPIOEX5")
			(pinfunction "~{PRSNT}")
			(pintype "input")
			(teardrops
				(best_length_ratio 0.2)
				(max_length 1)
				(best_width_ratio 0.9)
				(max_width 2)
				(curved_edges yes)
				(filter_ratio 0.9)
				(enabled yes)
				(allow_two_segments yes)
				(prefer_zone_connections yes)
			)
		)
		(pad "21" smd roundrect
			(at 0.75 -4.437 315)
			(size 0.25 0.875)
			(layers "B.Cu" "B.Mask" "B.Paste")
			(roundrect_rratio 0.25)
			(net 632 "Net-(U40-EN_{I2C})")
			(pinfunction "EN_{I2C}")
			(pintype "input")
			(teardrops
				(best_length_ratio 0.2)
				(max_length 1)
				(best_width_ratio 0.9)
				(max_width 2)
				(curved_edges yes)
				(filter_ratio 0.9)
				(enabled yes)
				(allow_two_segments yes)
				(prefer_zone_connections yes)
			)
		)
		(pad "22" smd roundrect
			(at 1.687 -4 315)
			(size 0.875 0.25)
			(layers "B.Cu" "B.Mask" "B.Paste")
			(roundrect_rratio 0.25)
			(net 718 "Net-(U40-I2C_{DONE})")
			(pinfunction "I2C_{DONE}")
			(pintype "input")
			(teardrops
				(best_length_ratio 0.2)
				(max_length 1)
				(best_width_ratio 0.9)
				(max_width 2)
				(curved_edges yes)
				(filter_ratio 0.9)
				(enabled yes)
				(allow_two_segments yes)
				(prefer_zone_connections yes)
			)
		)
		(pad "23" smd roundrect
			(at 1.687 -3.5 315)
			(size 0.875 0.25)
			(layers "B.Cu" "B.Mask" "B.Paste")
			(roundrect_rratio 0.25)
			(net 630 "Net-(U40-RXDET)")
			(pinfunction "RXDET")
			(pintype "input")
			(teardrops
				(best_length_ratio 0.2)
				(max_length 1)
				(best_width_ratio 0.9)
				(max_width 2)
				(curved_edges yes)
				(filter_ratio 0.9)
				(enabled yes)
				(allow_two_segments yes)
				(prefer_zone_connections yes)
			)
		)
		(pad "24" smd roundrect
			(at 1.687 -3 315)
			(size 0.875 0.25)
			(layers "B.Cu" "B.Mask" "B.Paste")
			(roundrect_rratio 0.25)
			(net 2 "+3V3")
			(pinfunction "VCC")
			(pintype "passive")
			(teardrops
				(best_length_ratio 0.2)
				(max_length 1)
				(best_width_ratio 0.9)
				(max_width 2)
				(curved_edges yes)
				(filter_ratio 0.9)
				(enabled yes)
				(allow_two_segments yes)
				(prefer_zone_connections yes)
			)
		)
		(pad "25" smd roundrect
			(at 1.687 -2.5 315)
			(size 0.875 0.25)
			(layers "B.Cu" "B.Mask" "B.Paste")
			(roundrect_rratio 0.25)
			(net 101 "/PCIe redriver/PCIe_{I}_C.RX0-")
			(pinfunction "A3TX-")
			(pintype "output")
			(teardrops
				(best_length_ratio 0.2)
				(max_length 1)
				(best_width_ratio 0.9)
				(max_width 2)
				(curved_edges yes)
				(filter_ratio 0.9)
				(enabled yes)
				(allow_two_segments yes)
				(prefer_zone_connections yes)
			)
		)
		(pad "26" smd roundrect
			(at 1.687001 -2 315)
			(size 0.875 0.25)
			(layers "B.Cu" "B.Mask" "B.Paste")
			(roundrect_rratio 0.25)
			(net 957 "/PCIe redriver/PCIe_{I}_C.RX0+")
			(pinfunction "A3TX+")
			(pintype "input")
			(teardrops
				(best_length_ratio 0.2)
				(max_length 1)
				(best_width_ratio 0.9)
				(max_width 2)
				(curved_edges yes)
				(filter_ratio 0.9)
				(enabled yes)
				(allow_two_segments yes)
				(prefer_zone_connections yes)
			)
		)
		(pad "27" smd roundrect
			(at 1.687 -1.5 315)
			(size 0.875 0.25)
			(layers "B.Cu" "B.Mask" "B.Paste")
			(roundrect_rratio 0.25)
			(net 2 "+3V3")
			(pinfunction "VCC")
			(pintype "passive")
			(teardrops
				(best_length_ratio 0.2)
				(max_length 1)
				(best_width_ratio 0.9)
				(max_width 2)
				(curved_edges yes)
				(filter_ratio 0.9)
				(enabled yes)
				(allow_two_segments yes)
				(prefer_zone_connections yes)
			)
		)
		(pad "28" smd roundrect
			(at 1.687 -1 315)
			(size 0.875 0.25)
			(layers "B.Cu" "B.Mask" "B.Paste")
			(roundrect_rratio 0.25)
			(net 103 "/PCIe redriver/PCIe_{I}_C.RX1-")
			(pinfunction "A2TX-")
			(pintype "output")
			(teardrops
				(best_length_ratio 0.2)
				(max_length 1)
				(best_width_ratio 0.9)
				(max_width 2)
				(curved_edges yes)
				(filter_ratio 0.9)
				(enabled yes)
				(allow_two_segments yes)
				(prefer_zone_connections yes)
			)
		)
	)
)
